#ISCELL
  mstr_misc dns *
  *
#ISCELL
  mstr_symbols design_note *
  *
#ISCELL
  mstr_symbols intel_corp_bpage *
  *
#CELL
  mstr_discrete ir354xx *
  page212_i101
#ISCELL
  mstr_symbols gnd *
  page212_i102
#CELL
  mstr_discrete res *
  page212_i103
#CELL
  mstr_misc shunt *
  page212_i104
#CELL
  mstr_misc shunt *
  page212_i105
#CELL
  dev_discrete cap_a *
  page212_i106
#ISCELL
  mstr_symbols gnd *
  page212_i107
#CELL
  mstr_discrete cap *
  page212_i109
#ISCELL
  mstr_symbols gnd *
  page212_i110
#CELL
  w_hdl sc2k2p50v3kx-gp *
  page212_i111
#CELL
  w_hdl 3d01r5f-gp *
  page212_i112
#ISCELL
  mstr_symbols gnd *
  page212_i113
#CELL
  mstr_discrete res *
  page212_i114
#ISCELL
  mstr_symbols gnd *
  page212_i13
#CELL
  mstr_discrete capp *
  page212_i16
#CELL
  mstr_discrete capp *
  page212_i17
#CELL
  mstr_discrete capp *
  page212_i18
#ISCELL
  mstr_standard offpage *
  page212_i19
#ISCELL
  mstr_standard offpage *
  page212_i20
#ISCELL
  mstr_standard offpage *
  page212_i21
#ISCELL
  mstr_symbols pvccio_cpu0 *
  page212_i22
#CELL
  dev_discrete cap_a *
  page212_i23
#ISCELL
  mstr_symbols gnd *
  page212_i24
#CELL
  mstr_discrete inductor *
  page212_i25
#ISCELL
  mstr_symbols gnd *
  page212_i29
#CELL
  mstr_discrete res *
  page212_i32
#CELL
  mstr_discrete cap *
  page212_i33
#CELL
  dev_discrete cap_a *
  page212_i34
#CELL
  mstr_discrete cap *
  page212_i36
#CELL
  mstr_discrete cap *
  page212_i37
#CELL
  dev_discrete cap_a *
  page212_i38
#CELL
  mstr_discrete cap *
  page212_i39
#CELL
  mstr_discrete cap *
  page212_i40
#CELL
  mstr_discrete cap *
  page212_i41
#CELL
  mstr_discrete cap *
  page212_i43
#ISCELL
  mstr_symbols gnd *
  page212_i44
#ISCELL
  mstr_standard offpage *
  page212_i45
#CELL
  mstr_discrete cap *
  page212_i51
#ISCELL
  mstr_symbols gnd *
  page212_i52
#CELL
  mstr_discrete cap *
  page212_i54
#ISCELL
  mstr_symbols gnd *
  page212_i55
#CELL
  mstr_discrete inductor *
  page212_i56
#ISCELL
  mstr_symbols p12v_stby *
  page212_i57
#ISCELL
  mstr_symbols p5v_stby *
  page212_i58
#ISCELL
  mstr_standard offpage *
  page212_i59
#CELL
  dev_discrete cap_a *
  page212_i60
#ISCELL
  mstr_standard offpage *
  page212_i61
#CELL
  mstr_discrete res *
  page212_i68
#ISCELL
  mstr_symbols gnd *
  page212_i69
#ISCELL
  mstr_standard offpage *
  page212_i70
#CELL
  mstr_discrete res *
  page212_i74
#ISCELL
  mstr_symbols pvccio_cpu0 *
  page212_i75
#ISCELL
  mstr_standard offpage *
  page212_i76
#CELL
  dev_discrete cap_a *
  page212_i77
#CELL
  mstr_discrete res *
  page212_i78
#ISCELL
  mstr_symbols vcc_core *
  page212_i79
#ISCELL
  mstr_symbols vcc_core *
  page212_i80
#ISCELL
  mstr_symbols pvccio_cpu0 *
  page212_i82
